FILE_TYPE = MULTI_PHYS_TABLE;

PART 'CONN_HDR_2X3_M_RA_TH'
CLASS = IO 

{========================================================================================}
:CLS_PN             = JEDEC_TYPE              |ALT_SYMBOLS               |DESCRIPTION                                       ;
{========================================================================================}
 'G200-11030-01'      = 'P_M_H_2X3_NP2_RA_P224'  |'(P_M_H_2X3_NP2_RA_P224)'  |'CON, MEGA-FIT,6 CIRCUITS,15U GOLD,RA HEADER,TH'
 'G200-11539-01'      = 'P_M_H_2X3_NP2_RA_P165'  |'(P_M_H_2X3_NP2_RA_P165)'  |'CON,6P,2X3,4.2MM PITCH,W/SHR,RA,TH'
 'G200-10748-01'      = 'P_M_H_2X3_S_P165'  |'(P_M_H_2X3_S_P165_COLUMBUS)'  |'CON, ATX POWER,6P,4.2MM,V/T,TH'  
 'G200-12158-01'      = 'P_M_H_2X3_NP1_RA_P118'  |'(P_M_H_2X3_NP1_RA_P118)'  |'CON,6PIN,2X3 DUAL,3MM PITCH, RIGHT ANGLE, TH'  
 'G200-12321-01'      = 'P_M_H_2X3_RA_P165_V1'  |'(P_M_H_2X3_RA_P165_V1)'  |'CON,POWER,6PINS,2X3,4.2MM,RA,TH' 
 'G200-12408-01'     = 'P_M_H_2X3_NP2_RA_P165_V1'  |'(P_M_H_2X3_NP2_RA_P165_V1)'  |'CON,6P,2X3,4.2MM PITCH,6 CKT R/A HEADER,TH' 
 'G200-12517-01'     = 'P_M_H_2X3_NP2_RA_P165_V1'  |'(P_M_H_2X3_NP2_RA_P165_V1)'  |'CON, 6P, 2X3, 4.2X4.2MM PITCH, R/A, BLACK, TH'
 'G200-12588-01'     = 'P_M_H_2X3_NP1_RA_P118_V1'  |'(P_M_H_2X3_NP1_RA_P118_V1)'  |'CON,6P,2X3,3X3MM PITCH,R/A,BLACK,TH' 
 'G200-12705-01'     = 'P_M_H_2X3_NP2_RA_P165_V2'  |'(P_M_H_2X3_NP2_RA_P165_V2)'  |'CON,6P,2X3,4.2MM PITCH,R/A,BLACK,TH' 
 'G200-12781-01'     = 'P_M_H_2X3_NP1_RA_P118_V2'  |'(P_M_H_2X3_NP1_RA_P118_V2)'  |'CON,HEADER,2X3 DUAL,WIRE-TO-BOARD,3.0MM PITCH,RA,TH' 


END_PART

END.

